(kicad_pcb
	(version 20260206)
	(generator "pcbnew")
	(generator_version "10.0")
	(general
		(thickness 1.6)
		(legacy_teardrops no)
	)
	(paper "A4")
	(title_block
		(title "12092022_DA0F0TMDCD0_F0T_Management_Board_D_brd_V3_OCP.brd")
		(comment 1 "Grand Teton / footprints 372-377 of 1440")
	)
	(layers
		(0 "F.Cu" signal "TOP")
		(4 "In1.Cu" signal "GND")
		(6 "In2.Cu" signal "IN1")
		(8 "In3.Cu" signal "GND1")
		(10 "In4.Cu" signal "IN2")
		(12 "In5.Cu" signal "VCC")
		(14 "In6.Cu" signal "VCC1")
		(16 "In7.Cu" signal "IN3")
		(18 "In8.Cu" signal "GND2")
		(20 "In9.Cu" signal "IN4")
		(22 "In10.Cu" signal "GND3")
		(2 "B.Cu" signal "BOTTOM")
		(9 "F.Adhes" user "F.Adhesive")
		(11 "B.Adhes" user "B.Adhesive")
		(13 "F.Paste" user "Package Geometry/Pastemask Top")
		(15 "B.Paste" user "Package Geometry/Pastemask Bottom")
		(5 "F.SilkS" user "Ref Des/Silkscreen Top")
		(7 "B.SilkS" user "Ref Des/Silkscreen Bottom")
		(1 "F.Mask" user "Board Geometry/Soldermask Top")
		(3 "B.Mask" user "Board Geometry/Soldermask Bottom")
		(17 "Dwgs.User" user "User.Drawings")
		(19 "Cmts.User" user "User.Comments")
		(21 "Eco1.User" user "User.Eco1")
		(23 "Eco2.User" user "User.Eco2")
		(25 "Edge.Cuts" user "Board Geometry/Outline")
		(27 "Margin" user)
		(31 "F.CrtYd" user "Package Geometry/Place Bound Top")
		(29 "B.CrtYd" user "Package Geometry/Place Bound Bottom")
		(35 "F.Fab" user "Ref Des/Assembly Top")
		(33 "B.Fab" user "Ref Des/Assembly Bottom")
	)
	(footprint ""
		(layer "F.Cu")
		(at 33.782 -44.45 90)
		(property "Reference" "C264"
			(at 0 0 90)
			(layer "F.SilkS")
			(hide yes)
			(effects
				(font
					(size 1.27 1.27)
				)
			)
		)
		(property "Value" ""
			(at 0 0 90)
			(layer "F.Fab")
			(effects
				(font
					(size 1.27 1.27)
				)
			)
		)
		(duplicate_pad_numbers_are_jumpers no)
		(fp_line
			(start 0.7874 -0.4064)
			(end 0.7874 0.4064)
			(stroke
				(width 0.1524)
				(type default)
			)
			(layer "F.SilkS")
		)
		(fp_line
			(start -0.7874 -0.4064)
			(end 0.7874 -0.4064)
			(stroke
				(width 0.1524)
				(type default)
			)
			(layer "F.SilkS")
		)
		(fp_line
			(start 0.7874 0.4064)
			(end -0.7874 0.4064)
			(stroke
				(width 0.1524)
				(type default)
			)
			(layer "F.SilkS")
		)
		(fp_line
			(start -0.7874 0.4064)
			(end -0.7874 -0.4064)
			(stroke
				(width 0.1524)
				(type default)
			)
			(layer "F.SilkS")
		)
		(fp_line
			(start -0.12065 -0.305054)
			(end -0.12065 -0.2794)
			(stroke
				(width 0.1)
				(type default)
			)
			(layer "F.Fab")
		)
		(fp_line
			(start -0.67945 -0.305054)
			(end -0.12065 -0.305054)
			(stroke
				(width 0.1)
				(type default)
			)
			(layer "F.Fab")
		)
		(fp_line
			(start 0.67945 -0.3048)
			(end 0.67945 0.3048)
			(stroke
				(width 0.1)
				(type default)
			)
			(layer "F.Fab")
		)
		(fp_line
			(start 0.12065 -0.3048)
			(end 0.67945 -0.3048)
			(stroke
				(width 0.1)
				(type default)
			)
			(layer "F.Fab")
		)
		(fp_line
			(start 0.12065 -0.2794)
			(end 0.12065 -0.3048)
			(stroke
				(width 0.1)
				(type default)
			)
			(layer "F.Fab")
		)
		(fp_line
			(start -0.12065 -0.2794)
			(end 0.12065 -0.2794)
			(stroke
				(width 0.1)
				(type default)
			)
			(layer "F.Fab")
		)
		(fp_line
			(start 0.120396 0.2794)
			(end -0.12065 0.2794)
			(stroke
				(width 0.1)
				(type default)
			)
			(layer "F.Fab")
		)
		(fp_line
			(start -0.12065 0.2794)
			(end -0.12065 0.3048)
			(stroke
				(width 0.1)
				(type default)
			)
			(layer "F.Fab")
		)
		(fp_line
			(start 0.67945 0.3048)
			(end 0.120396 0.3048)
			(stroke
				(width 0.1)
				(type default)
			)
			(layer "F.Fab")
		)
		(fp_line
			(start 0.120396 0.3048)
			(end 0.120396 0.2794)
			(stroke
				(width 0.1)
				(type default)
			)
			(layer "F.Fab")
		)
		(fp_line
			(start -0.12065 0.3048)
			(end -0.67945 0.3048)
			(stroke
				(width 0.1)
				(type default)
			)
			(layer "F.Fab")
		)
		(fp_line
			(start -0.67945 0.3048)
			(end -0.67945 -0.305054)
			(stroke
				(width 0.1)
				(type default)
			)
			(layer "F.Fab")
		)
		(pad "1" smd circle
			(at -0.40005 0 90)
			(size 0 0)
			(layers "F.Cu" "F.Mask" "F.Paste")
			(net "U43_CT")
		)
		(pad "2" smd circle
			(at 0.40005 0 90)
			(size 0 0)
			(layers "F.Cu" "F.Mask" "F.Paste")
			(net "GND")
		)
	)
	(footprint ""
		(layer "F.Cu")
		(at 29.729938 -6.290056)
		(property "Reference" "D13"
			(at 1.512062 -2.624074 0)
			(unlocked yes)
			(layer "F.SilkS")
			(effects
				(font
					(size 0.7874 0.5842)
					(thickness 0.1524)
				)
				(justify left)
			)
		)
		(property "Value" ""
			(at 0 0 0)
			(layer "F.Fab")
			(effects
				(font
					(size 1.27 1.27)
				)
			)
		)
		(duplicate_pad_numbers_are_jumpers no)
		(fp_line
			(start -0.979932 -2.100072)
			(end 3.519932 -2.100072)
			(stroke
				(width 0.1524)
				(type default)
			)
			(layer "F.SilkS")
		)
		(fp_line
			(start -0.979932 3.899916)
			(end -0.979932 -2.100072)
			(stroke
				(width 0.1524)
				(type default)
			)
			(layer "F.SilkS")
		)
		(fp_line
			(start -0.130048 3.899916)
			(end -0.979932 3.899916)
			(stroke
				(width 0.1524)
				(type default)
			)
			(layer "F.SilkS")
		)
		(fp_line
			(start -0.130048 4.800092)
			(end -0.130048 3.899916)
			(stroke
				(width 0.1524)
				(type default)
			)
			(layer "F.SilkS")
		)
		(fp_line
			(start 2.670048 3.899916)
			(end 2.670048 4.800092)
			(stroke
				(width 0.1524)
				(type default)
			)
			(layer "F.SilkS")
		)
		(fp_line
			(start 3.519932 -2.100072)
			(end 3.519932 3.899916)
			(stroke
				(width 0.1524)
				(type default)
			)
			(layer "F.SilkS")
		)
		(fp_line
			(start 3.519932 3.899916)
			(end 2.670048 3.899916)
			(stroke
				(width 0.1524)
				(type default)
			)
			(layer "F.SilkS")
		)
		(fp_arc
			(start 1.27 6.199886)
			(mid 0.280106 5.789911)
			(end -0.130048 4.800092)
			(stroke
				(width 0.1524)
				(type default)
			)
			(layer "F.SilkS")
		)
		(fp_arc
			(start 2.670048 4.800092)
			(mid 2.259894 5.789911)
			(end 1.27 6.199886)
			(stroke
				(width 0.1524)
				(type default)
			)
			(layer "F.SilkS")
		)
		(fp_line
			(start -0.979932 -2.100072)
			(end 3.519932 -2.100072)
			(stroke
				(width 0.1)
				(type default)
			)
			(layer "F.Fab")
		)
		(fp_line
			(start -0.979932 3.899916)
			(end -0.979932 -2.100072)
			(stroke
				(width 0.1)
				(type default)
			)
			(layer "F.Fab")
		)
		(fp_line
			(start -0.130048 3.899916)
			(end -0.979932 3.899916)
			(stroke
				(width 0.1)
				(type default)
			)
			(layer "F.Fab")
		)
		(fp_line
			(start -0.130048 4.800092)
			(end -0.130048 3.899916)
			(stroke
				(width 0.1)
				(type default)
			)
			(layer "F.Fab")
		)
		(fp_line
			(start 2.670048 3.899916)
			(end 2.670048 4.800092)
			(stroke
				(width 0.1)
				(type default)
			)
			(layer "F.Fab")
		)
		(fp_line
			(start 3.519932 -2.100072)
			(end 3.519932 3.899916)
			(stroke
				(width 0.1)
				(type default)
			)
			(layer "F.Fab")
		)
		(fp_line
			(start 3.519932 3.899916)
			(end 2.670048 3.899916)
			(stroke
				(width 0.1)
				(type default)
			)
			(layer "F.Fab")
		)
		(fp_arc
			(start 1.27 6.199886)
			(mid 0.280106 5.789911)
			(end -0.130048 4.800092)
			(stroke
				(width 0.1)
				(type default)
			)
			(layer "F.Fab")
		)
		(fp_arc
			(start 2.670048 4.800092)
			(mid 2.259894 5.789911)
			(end 1.27 6.199886)
			(stroke
				(width 0.1)
				(type default)
			)
			(layer "F.Fab")
		)
		(pad "A" thru_hole rect
			(at 0 0)
			(size 1.2192 1.2192)
			(drill 0.8128)
			(layers "*.Cu" "*.Mask")
			(remove_unused_layers no)
			(net "ID_LED_P3V3_AUX")
			(clearance 0.0508)
			(thermal_gap 0.0508)
			(padstack
				(mode front_inner_back)
				(layer "Inner"
					(shape circle)
					(size 1.2192 1.2192)
					(clearance 0.0508)
				)
				(layer "B.Cu"
					(shape rect)
					(size 1.2192 1.2192)
					(clearance 0.0508)
				)
			)
		)
		(pad "C" thru_hole circle
			(at 2.54 0)
			(size 1.2192 1.2192)
			(drill 0.8128)
			(layers "*.Cu" "*.Mask")
			(remove_unused_layers no)
			(net "ID_LED_D_P3V3_AUX")
			(clearance 0.0508)
			(thermal_gap 0.0508)
		)
	)
	(footprint ""
		(layer "F.Cu")
		(at 23.34895 -30.631384 -90)
		(property "Reference" "PR541"
			(at 0 0 270)
			(layer "F.SilkS")
			(hide yes)
			(effects
				(font
					(size 1.27 1.27)
				)
			)
		)
		(property "Value" ""
			(at 0 0 270)
			(layer "F.Fab")
			(effects
				(font
					(size 1.27 1.27)
				)
			)
		)
		(duplicate_pad_numbers_are_jumpers no)
		(fp_line
			(start -0.7874 0.4064)
			(end -0.7874 -0.4064)
			(stroke
				(width 0.1524)
				(type default)
			)
			(layer "F.SilkS")
		)
		(fp_line
			(start 0.7874 0.4064)
			(end -0.7874 0.4064)
			(stroke
				(width 0.1524)
				(type default)
			)
			(layer "F.SilkS")
		)
		(fp_line
			(start -0.7874 -0.4064)
			(end 0.7874 -0.4064)
			(stroke
				(width 0.1524)
				(type default)
			)
			(layer "F.SilkS")
		)
		(fp_line
			(start 0.7874 -0.4064)
			(end 0.7874 0.4064)
			(stroke
				(width 0.1524)
				(type default)
			)
			(layer "F.SilkS")
		)
		(fp_line
			(start -0.67945 0.3048)
			(end -0.67945 -0.305054)
			(stroke
				(width 0.1)
				(type default)
			)
			(layer "F.Fab")
		)
		(fp_line
			(start -0.12065 0.3048)
			(end -0.67945 0.3048)
			(stroke
				(width 0.1)
				(type default)
			)
			(layer "F.Fab")
		)
		(fp_line
			(start 0.120396 0.3048)
			(end 0.120396 0.2794)
			(stroke
				(width 0.1)
				(type default)
			)
			(layer "F.Fab")
		)
		(fp_line
			(start 0.67945 0.3048)
			(end 0.120396 0.3048)
			(stroke
				(width 0.1)
				(type default)
			)
			(layer "F.Fab")
		)
		(fp_line
			(start -0.12065 0.2794)
			(end -0.12065 0.3048)
			(stroke
				(width 0.1)
				(type default)
			)
			(layer "F.Fab")
		)
		(fp_line
			(start 0.120396 0.2794)
			(end -0.12065 0.2794)
			(stroke
				(width 0.1)
				(type default)
			)
			(layer "F.Fab")
		)
		(fp_line
			(start -0.12065 -0.2794)
			(end 0.12065 -0.2794)
			(stroke
				(width 0.1)
				(type default)
			)
			(layer "F.Fab")
		)
		(fp_line
			(start 0.12065 -0.2794)
			(end 0.12065 -0.3048)
			(stroke
				(width 0.1)
				(type default)
			)
			(layer "F.Fab")
		)
		(fp_line
			(start 0.12065 -0.3048)
			(end 0.67945 -0.3048)
			(stroke
				(width 0.1)
				(type default)
			)
			(layer "F.Fab")
		)
		(fp_line
			(start 0.67945 -0.3048)
			(end 0.67945 0.3048)
			(stroke
				(width 0.1)
				(type default)
			)
			(layer "F.Fab")
		)
		(fp_line
			(start -0.67945 -0.305054)
			(end -0.12065 -0.305054)
			(stroke
				(width 0.1)
				(type default)
			)
			(layer "F.Fab")
		)
		(fp_line
			(start -0.12065 -0.305054)
			(end -0.12065 -0.2794)
			(stroke
				(width 0.1)
				(type default)
			)
			(layer "F.Fab")
		)
		(pad "1" smd circle
			(at -0.40005 0 270)
			(size 0 0)
			(layers "F.Cu" "F.Mask" "F.Paste")
			(net "PVCC2_AUX")
		)
		(pad "2" smd circle
			(at 0.40005 0 270)
			(size 0 0)
			(layers "F.Cu" "F.Mask" "F.Paste")
			(net "P1V0_AUX_VCC")
		)
	)
	(footprint ""
		(layer "F.Cu")
		(at 79.739744 -35.527488 90)
		(property "Reference" "R348"
			(at 0 0 90)
			(layer "F.SilkS")
			(hide yes)
			(effects
				(font
					(size 1.27 1.27)
				)
			)
		)
		(property "Value" ""
			(at 0 0 90)
			(layer "F.Fab")
			(effects
				(font
					(size 1.27 1.27)
				)
			)
		)
		(duplicate_pad_numbers_are_jumpers no)
		(fp_line
			(start 0.7874 -0.4064)
			(end 0.7874 0.4064)
			(stroke
				(width 0.1524)
				(type default)
			)
			(layer "F.SilkS")
		)
		(fp_line
			(start -0.7874 -0.4064)
			(end 0.7874 -0.4064)
			(stroke
				(width 0.1524)
				(type default)
			)
			(layer "F.SilkS")
		)
		(fp_line
			(start 0.7874 0.4064)
			(end -0.7874 0.4064)
			(stroke
				(width 0.1524)
				(type default)
			)
			(layer "F.SilkS")
		)
		(fp_line
			(start -0.7874 0.4064)
			(end -0.7874 -0.4064)
			(stroke
				(width 0.1524)
				(type default)
			)
			(layer "F.SilkS")
		)
		(fp_line
			(start -0.12065 -0.305054)
			(end -0.12065 -0.2794)
			(stroke
				(width 0.1)
				(type default)
			)
			(layer "F.Fab")
		)
		(fp_line
			(start -0.67945 -0.305054)
			(end -0.12065 -0.305054)
			(stroke
				(width 0.1)
				(type default)
			)
			(layer "F.Fab")
		)
		(fp_line
			(start 0.67945 -0.3048)
			(end 0.67945 0.3048)
			(stroke
				(width 0.1)
				(type default)
			)
			(layer "F.Fab")
		)
		(fp_line
			(start 0.12065 -0.3048)
			(end 0.67945 -0.3048)
			(stroke
				(width 0.1)
				(type default)
			)
			(layer "F.Fab")
		)
		(fp_line
			(start 0.12065 -0.2794)
			(end 0.12065 -0.3048)
			(stroke
				(width 0.1)
				(type default)
			)
			(layer "F.Fab")
		)
		(fp_line
			(start -0.12065 -0.2794)
			(end 0.12065 -0.2794)
			(stroke
				(width 0.1)
				(type default)
			)
			(layer "F.Fab")
		)
		(fp_line
			(start 0.120396 0.2794)
			(end -0.12065 0.2794)
			(stroke
				(width 0.1)
				(type default)
			)
			(layer "F.Fab")
		)
		(fp_line
			(start -0.12065 0.2794)
			(end -0.12065 0.3048)
			(stroke
				(width 0.1)
				(type default)
			)
			(layer "F.Fab")
		)
		(fp_line
			(start 0.67945 0.3048)
			(end 0.120396 0.3048)
			(stroke
				(width 0.1)
				(type default)
			)
			(layer "F.Fab")
		)
		(fp_line
			(start 0.120396 0.3048)
			(end 0.120396 0.2794)
			(stroke
				(width 0.1)
				(type default)
			)
			(layer "F.Fab")
		)
		(fp_line
			(start -0.12065 0.3048)
			(end -0.67945 0.3048)
			(stroke
				(width 0.1)
				(type default)
			)
			(layer "F.Fab")
		)
		(fp_line
			(start -0.67945 0.3048)
			(end -0.67945 -0.305054)
			(stroke
				(width 0.1)
				(type default)
			)
			(layer "F.Fab")
		)
		(pad "1" smd circle
			(at -0.40005 0 90)
			(size 0 0)
			(layers "F.Cu" "F.Mask" "F.Paste")
			(net "GND")
		)
		(pad "2" smd circle
			(at 0.40005 0 90)
			(size 0 0)
			(layers "F.Cu" "F.Mask" "F.Paste")
			(net "M_BMC_DDR4_MODT")
		)
	)
	(footprint ""
		(layer "F.Cu")
		(at 51.19116 -23.450804 180)
		(property "Reference" "U10"
			(at 1.97866 2.138426 0)
			(unlocked yes)
			(layer "F.SilkS")
			(effects
				(font
					(size 0.7874 0.5842)
					(thickness 0.1524)
				)
				(justify left)
			)
		)
		(property "Value" ""
			(at 0 0 180)
			(layer "F.Fab")
			(effects
				(font
					(size 1.27 1.27)
				)
			)
		)
		(duplicate_pad_numbers_are_jumpers no)
		(fp_line
			(start 1.738884 1.549908)
			(end 1.738884 -1.549908)
			(stroke
				(width 0.1524)
				(type default)
			)
			(layer "F.SilkS")
		)
		(fp_line
			(start 1.738884 -1.549908)
			(end 0.635508 -1.549908)
			(stroke
				(width 0.1524)
				(type default)
			)
			(layer "F.SilkS")
		)
		(fp_line
			(start 0.635508 -1.549908)
			(end 0 -0.9144)
			(stroke
				(width 0.1524)
				(type default)
			)
			(layer "F.SilkS")
		)
		(fp_line
			(start 0 -0.9144)
			(end -0.635508 -1.549908)
			(stroke
				(width 0.1524)
				(type default)
			)
			(layer "F.SilkS")
		)
		(fp_line
			(start -0.635508 -1.549908)
			(end -1.738884 -1.549908)
			(stroke
				(width 0.1524)
				(type default)
			)
			(layer "F.SilkS")
		)
		(fp_line
			(start -1.738884 1.549908)
			(end 1.738884 1.549908)
			(stroke
				(width 0.1524)
				(type default)
			)
			(layer "F.SilkS")
		)
		(fp_line
			(start -1.738884 -1.549908)
			(end -1.738884 1.549908)
			(stroke
				(width 0.1524)
				(type default)
			)
			(layer "F.SilkS")
		)
		(fp_poly
			(pts
				(xy -2.445766 -1.211326) (xy -1.923034 -0.94996) (xy -2.445766 -0.688594)
			)
			(stroke
				(width 0)
				(type default)
			)
			(fill yes)
			(layer "F.SilkS")
		)
		(fp_line
			(start 0.849884 1.549908)
			(end 0.849884 -1.549908)
			(stroke
				(width 0.1)
				(type default)
			)
			(layer "F.Fab")
		)
		(fp_line
			(start 0.849884 -1.549908)
			(end -0.849884 -1.549908)
			(stroke
				(width 0.1)
				(type default)
			)
			(layer "F.Fab")
		)
		(fp_line
			(start -0.849884 1.549908)
			(end 0.849884 1.549908)
			(stroke
				(width 0.1)
				(type default)
			)
			(layer "F.Fab")
		)
		(fp_line
			(start -0.849884 -1.549908)
			(end -0.849884 1.549908)
			(stroke
				(width 0.1)
				(type default)
			)
			(layer "F.Fab")
		)
		(fp_poly
			(pts
				(xy -2.445766 -1.211326) (xy -1.923034 -0.94996) (xy -2.445766 -0.688594)
			)
			(stroke
				(width 0)
				(type default)
			)
			(fill yes)
			(layer "F.Fab")
		)
		(pad "1" smd rect
			(at -1.124966 -0.94996 270)
			(size 0.6096 0.9652)
			(layers "F.Cu" "F.Mask" "F.Paste")
			(net "P5V_AUX")
		)
		(pad "2" smd rect
			(at -1.124966 0 270)
			(size 0.6096 0.9652)
			(layers "F.Cu" "F.Mask" "F.Paste")
			(net "GND")
		)
		(pad "3" smd rect
			(at -1.124966 0.94996 270)
			(size 0.6096 0.9652)
			(layers "F.Cu" "F.Mask" "F.Paste")
			(net "USB_OC0_EN")
		)
		(pad "4" smd rect
			(at 1.124966 0.94996 270)
			(size 0.6096 0.9652)
			(layers "F.Cu" "F.Mask" "F.Paste")
			(net "USB_OC0_REAR_N")
		)
		(pad "5" smd rect
			(at 1.124966 0 270)
			(size 0.6096 0.9652)
			(layers "F.Cu" "F.Mask" "F.Paste")
			(net "USB_OC0_ILIM")
		)
		(pad "6" smd rect
			(at 1.124966 -0.94996 270)
			(size 0.6096 0.9652)
			(layers "F.Cu" "F.Mask" "F.Paste")
			(net "P5V_USB_REAR")
		)
	)
	(footprint ""
		(layer "F.Cu")
		(at 55.9054 -21.4884 -90)
		(property "Reference" "C171"
			(at 0 0 270)
			(layer "F.SilkS")
			(hide yes)
			(effects
				(font
					(size 1.27 1.27)
				)
			)
		)
		(property "Value" ""
			(at 0 0 270)
			(layer "F.Fab")
			(effects
				(font
					(size 1.27 1.27)
				)
			)
		)
		(duplicate_pad_numbers_are_jumpers no)
		(fp_line
			(start -1.651 0.8382)
			(end -1.651 -0.8382)
			(stroke
				(width 0.1524)
				(type default)
			)
			(layer "F.SilkS")
		)
		(fp_line
			(start 0 0.8382)
			(end 0 -0.8382)
			(stroke
				(width 0.1524)
				(type default)
			)
			(layer "F.SilkS")
		)
		(fp_line
			(start 1.651 0.8382)
			(end -1.651 0.8382)
			(stroke
				(width 0.1524)
				(type default)
			)
			(layer "F.SilkS")
		)
		(fp_line
			(start -1.651 -0.8382)
			(end 1.651 -0.8382)
			(stroke
				(width 0.1524)
				(type default)
			)
			(layer "F.SilkS")
		)
		(fp_line
			(start 1.651 -0.8382)
			(end 1.651 0.8382)
			(stroke
				(width 0.1524)
				(type default)
			)
			(layer "F.SilkS")
		)
		(fp_line
			(start -1.55956 0.7366)
			(end -1.524 0.7366)
			(stroke
				(width 0.1)
				(type default)
			)
			(layer "F.Fab")
		)
		(fp_line
			(start -1.524 0.7366)
			(end 1.524 0.7366)
			(stroke
				(width 0.1)
				(type default)
			)
			(layer "F.Fab")
		)
		(fp_line
			(start 1.524 0.7366)
			(end 1.55956 0.7366)
			(stroke
				(width 0.1)
				(type default)
			)
			(layer "F.Fab")
		)
		(fp_line
			(start 1.55956 0.7366)
			(end 1.55956 -0.7366)
			(stroke
				(width 0.1)
				(type default)
			)
			(layer "F.Fab")
		)
		(fp_line
			(start -1.55956 -0.7366)
			(end -1.55956 0.7366)
			(stroke
				(width 0.1)
				(type default)
			)
			(layer "F.Fab")
		)
		(fp_line
			(start -1.524 -0.7366)
			(end -1.55956 -0.7366)
			(stroke
				(width 0.1)
				(type default)
			)
			(layer "F.Fab")
		)
		(fp_line
			(start 1.524 -0.7366)
			(end -1.524 -0.7366)
			(stroke
				(width 0.1)
				(type default)
			)
			(layer "F.Fab")
		)
		(fp_line
			(start 1.55956 -0.7366)
			(end 1.524 -0.7366)
			(stroke
				(width 0.1)
				(type default)
			)
			(layer "F.Fab")
		)
		(pad "1" smd rect
			(at -0.94996 0 90)
			(size 1.1176 1.3716)
			(layers "F.Cu" "F.Mask" "F.Paste")
			(net "P5V_AUX")
		)
		(pad "2" smd rect
			(at 0.94996 0 90)
			(size 1.1176 1.3716)
			(layers "F.Cu" "F.Mask" "F.Paste")
			(net "GND")
		)
	)
)
